(kicad_pcb
	(version 20260206)
	(generator "pcbnew")
	(generator_version "10.0")
	(general
		(thickness 1.6)
		(legacy_teardrops no)
	)
	(paper "A4")
	(title_block
		(title "01162023_DA0F0TEBIF0_F0T_Expander_BD_F_brd_V02_OCP.brd")
		(comment 1 "Grand Teton / footprints 3628-3633 of 9728")
	)
	(layers
		(0 "F.Cu" signal "TOP")
		(4 "In1.Cu" signal "GND")
		(6 "In2.Cu" signal "VCC")
		(8 "In3.Cu" signal "VCC1")
		(10 "In4.Cu" signal "GND1")
		(12 "In5.Cu" signal "IN1")
		(14 "In6.Cu" signal "GND2")
		(16 "In7.Cu" signal "IN2")
		(18 "In8.Cu" signal "GND3")
		(20 "In9.Cu" signal "IN3")
		(22 "In10.Cu" signal "GND4")
		(24 "In11.Cu" signal "IN4")
		(26 "In12.Cu" signal "GND5")
		(28 "In13.Cu" signal "IN5")
		(30 "In14.Cu" signal "GND6")
		(32 "In15.Cu" signal "IN6")
		(34 "In16.Cu" signal "GND7")
		(2 "B.Cu" signal "BOTTOM")
		(9 "F.Adhes" user "F.Adhesive")
		(11 "B.Adhes" user "B.Adhesive")
		(13 "F.Paste" user "Package Geometry/Pastemask Top")
		(15 "B.Paste" user "Package Geometry/Pastemask Bottom")
		(5 "F.SilkS" user "Ref Des/Silkscreen Top")
		(7 "B.SilkS" user "Ref Des/Silkscreen Bottom")
		(1 "F.Mask" user "Board Geometry/Soldermask Top")
		(3 "B.Mask" user "Board Geometry/Soldermask Bottom")
		(17 "Dwgs.User" user "User.Drawings")
		(19 "Cmts.User" user "User.Comments")
		(21 "Eco1.User" user "User.Eco1")
		(23 "Eco2.User" user "User.Eco2")
		(25 "Edge.Cuts" user "Board Geometry/Outline")
		(27 "Margin" user)
		(31 "F.CrtYd" user "Package Geometry/Place Bound Top")
		(29 "B.CrtYd" user "Package Geometry/Place Bound Bottom")
		(35 "F.Fab" user "Ref Des/Assembly Top")
		(33 "B.Fab" user "Ref Des/Assembly Bottom")
	)
	(footprint ""
		(layer "F.Cu")
		(at 304.775362 -69.47916 180)
		(property "Reference" "PU114"
			(at -1.956308 4.07924 90)
			(unlocked yes)
			(layer "F.SilkS")
			(effects
				(font
					(size 0.7874 0.5842)
					(thickness 0.1524)
				)
			)
		)
		(property "Value" ""
			(at 0 0 180)
			(layer "F.Fab")
			(effects
				(font
					(size 1.27 1.27)
				)
			)
		)
		(duplicate_pad_numbers_are_jumpers no)
		(fp_line
			(start 1.239774 1.495298)
			(end -1.239774 1.495298)
			(stroke
				(width 0.1524)
				(type default)
			)
			(layer "F.SilkS")
		)
		(fp_line
			(start 1.239774 -1.495298)
			(end 1.239774 1.495298)
			(stroke
				(width 0.1524)
				(type default)
			)
			(layer "F.SilkS")
		)
		(fp_line
			(start -1.239774 1.495298)
			(end -1.239774 -1.495298)
			(stroke
				(width 0.1524)
				(type default)
			)
			(layer "F.SilkS")
		)
		(fp_line
			(start -1.239774 -1.495298)
			(end 1.239774 -1.495298)
			(stroke
				(width 0.1524)
				(type default)
			)
			(layer "F.SilkS")
		)
		(fp_poly
			(pts
				(xy -1.684274 -1.175766) (xy -2.402586 -0.457454) (xy -1.324864 -0.098298)
			)
			(stroke
				(width 0)
				(type default)
			)
			(fill yes)
			(layer "F.SilkS")
		)
		(fp_line
			(start 0.8001 1.050036)
			(end -0.8001 1.050036)
			(stroke
				(width 0.1)
				(type default)
			)
			(layer "F.Fab")
		)
		(fp_line
			(start 0.8001 -1.050036)
			(end 0.8001 1.050036)
			(stroke
				(width 0.1)
				(type default)
			)
			(layer "F.Fab")
		)
		(fp_line
			(start -0.8001 1.050036)
			(end -0.8001 -1.050036)
			(stroke
				(width 0.1)
				(type default)
			)
			(layer "F.Fab")
		)
		(fp_line
			(start -0.8001 -1.050036)
			(end 0.8001 -1.050036)
			(stroke
				(width 0.1)
				(type default)
			)
			(layer "F.Fab")
		)
		(fp_poly
			(pts
				(xy -2.458974 -0.508) (xy -2.458974 0.508) (xy -1.442974 0)
			)
			(stroke
				(width 0)
				(type default)
			)
			(fill yes)
			(layer "F.Fab")
		)
		(pad "1_2" smd circle
			(at -0.374904 0 270)
			(size 0 0)
			(layers "F.Cu" "F.Mask" "F.Paste")
			(net "P12V_AUX")
		)
		(pad "3" smd rect
			(at -0.499872 0.999998 180)
			(size 0.254 0.7112)
			(layers "F.Cu" "F.Mask" "F.Paste")
			(net "GND")
		)
		(pad "4" smd rect
			(at 0 0.999998 180)
			(size 0.254 0.7112)
			(layers "F.Cu" "F.Mask" "F.Paste")
			(net "P12V_SSD10_CO_ILIMIT")
		)
		(pad "5" smd rect
			(at 0.499872 0.999998 180)
			(size 0.254 0.7112)
			(layers "F.Cu" "F.Mask" "F.Paste")
			(net "P12V_SSD10_CO_MODE")
		)
		(pad "6_7" smd circle
			(at 0.374904 0 90)
			(size 0 0)
			(layers "F.Cu" "F.Mask" "F.Paste")
			(net "P12V_SSD10_R")
		)
		(pad "8" smd rect
			(at 0.499872 -0.999998 180)
			(size 0.254 0.7112)
			(layers "F.Cu" "F.Mask" "F.Paste")
			(net "P12V_SSD10_CO_GATE")
		)
		(pad "9" smd rect
			(at 0 -0.999998 180)
			(size 0.254 0.7112)
			(layers "F.Cu" "F.Mask" "F.Paste")
			(net "P12V_SSD10_CO_EN")
		)
		(pad "10" smd rect
			(at -0.499872 -0.999998 180)
			(size 0.254 0.7112)
			(layers "F.Cu" "F.Mask" "F.Paste")
			(net "P12V_SSD10_CO_DV_DT")
		)
	)
	(footprint ""
		(layer "F.Cu")
		(at 118.975378 -63.086234)
		(property "Reference" "R5978"
			(at 0 0 0)
			(layer "F.SilkS")
			(hide yes)
			(effects
				(font
					(size 1.27 1.27)
				)
			)
		)
		(property "Value" ""
			(at 0 0 0)
			(layer "F.Fab")
			(effects
				(font
					(size 1.27 1.27)
				)
			)
		)
		(duplicate_pad_numbers_are_jumpers no)
		(fp_line
			(start -0.7874 -0.4064)
			(end 0.7874 -0.4064)
			(stroke
				(width 0.1524)
				(type default)
			)
			(layer "F.SilkS")
		)
		(fp_line
			(start -0.7874 0.4064)
			(end -0.7874 -0.4064)
			(stroke
				(width 0.1524)
				(type default)
			)
			(layer "F.SilkS")
		)
		(fp_line
			(start 0.7874 -0.4064)
			(end 0.7874 0.4064)
			(stroke
				(width 0.1524)
				(type default)
			)
			(layer "F.SilkS")
		)
		(fp_line
			(start 0.7874 0.4064)
			(end -0.7874 0.4064)
			(stroke
				(width 0.1524)
				(type default)
			)
			(layer "F.SilkS")
		)
		(fp_line
			(start -0.67945 -0.305054)
			(end -0.12065 -0.305054)
			(stroke
				(width 0.1)
				(type default)
			)
			(layer "F.Fab")
		)
		(fp_line
			(start -0.67945 0.3048)
			(end -0.67945 -0.305054)
			(stroke
				(width 0.1)
				(type default)
			)
			(layer "F.Fab")
		)
		(fp_line
			(start -0.12065 -0.305054)
			(end -0.12065 -0.2794)
			(stroke
				(width 0.1)
				(type default)
			)
			(layer "F.Fab")
		)
		(fp_line
			(start -0.12065 -0.2794)
			(end 0.12065 -0.2794)
			(stroke
				(width 0.1)
				(type default)
			)
			(layer "F.Fab")
		)
		(fp_line
			(start -0.12065 0.2794)
			(end -0.12065 0.3048)
			(stroke
				(width 0.1)
				(type default)
			)
			(layer "F.Fab")
		)
		(fp_line
			(start -0.12065 0.3048)
			(end -0.67945 0.3048)
			(stroke
				(width 0.1)
				(type default)
			)
			(layer "F.Fab")
		)
		(fp_line
			(start 0.120396 0.2794)
			(end -0.12065 0.2794)
			(stroke
				(width 0.1)
				(type default)
			)
			(layer "F.Fab")
		)
		(fp_line
			(start 0.120396 0.3048)
			(end 0.120396 0.2794)
			(stroke
				(width 0.1)
				(type default)
			)
			(layer "F.Fab")
		)
		(fp_line
			(start 0.12065 -0.3048)
			(end 0.67945 -0.3048)
			(stroke
				(width 0.1)
				(type default)
			)
			(layer "F.Fab")
		)
		(fp_line
			(start 0.12065 -0.2794)
			(end 0.12065 -0.3048)
			(stroke
				(width 0.1)
				(type default)
			)
			(layer "F.Fab")
		)
		(fp_line
			(start 0.67945 -0.3048)
			(end 0.67945 0.3048)
			(stroke
				(width 0.1)
				(type default)
			)
			(layer "F.Fab")
		)
		(fp_line
			(start 0.67945 0.3048)
			(end 0.120396 0.3048)
			(stroke
				(width 0.1)
				(type default)
			)
			(layer "F.Fab")
		)
		(pad "1" smd circle
			(at -0.40005 0)
			(size 0 0)
			(layers "F.Cu" "F.Mask" "F.Paste")
			(net "P12V_SSD4_R")
		)
		(pad "2" smd circle
			(at 0.40005 0)
			(size 0 0)
			(layers "F.Cu" "F.Mask" "F.Paste")
			(net "P12V_SSD4_PG_G1")
		)
	)
	(footprint ""
		(layer "F.Cu")
		(at 62.215268 -393.16279 -90)
		(property "Reference" "C4014"
			(at 0 0 270)
			(layer "F.SilkS")
			(hide yes)
			(effects
				(font
					(size 1.27 1.27)
				)
			)
		)
		(property "Value" ""
			(at 0 0 270)
			(layer "F.Fab")
			(effects
				(font
					(size 1.27 1.27)
				)
			)
		)
		(duplicate_pad_numbers_are_jumpers no)
		(fp_line
			(start -0.7874 0.4064)
			(end -0.7874 -0.4064)
			(stroke
				(width 0.1524)
				(type default)
			)
			(layer "F.SilkS")
		)
		(fp_line
			(start 0.7874 0.4064)
			(end -0.7874 0.4064)
			(stroke
				(width 0.1524)
				(type default)
			)
			(layer "F.SilkS")
		)
		(fp_line
			(start -0.7874 -0.4064)
			(end 0.7874 -0.4064)
			(stroke
				(width 0.1524)
				(type default)
			)
			(layer "F.SilkS")
		)
		(fp_line
			(start 0.7874 -0.4064)
			(end 0.7874 0.4064)
			(stroke
				(width 0.1524)
				(type default)
			)
			(layer "F.SilkS")
		)
		(fp_line
			(start -0.67945 0.3048)
			(end -0.67945 -0.305054)
			(stroke
				(width 0.1)
				(type default)
			)
			(layer "F.Fab")
		)
		(fp_line
			(start -0.12065 0.3048)
			(end -0.67945 0.3048)
			(stroke
				(width 0.1)
				(type default)
			)
			(layer "F.Fab")
		)
		(fp_line
			(start 0.120396 0.3048)
			(end 0.120396 0.2794)
			(stroke
				(width 0.1)
				(type default)
			)
			(layer "F.Fab")
		)
		(fp_line
			(start 0.67945 0.3048)
			(end 0.120396 0.3048)
			(stroke
				(width 0.1)
				(type default)
			)
			(layer "F.Fab")
		)
		(fp_line
			(start -0.12065 0.2794)
			(end -0.12065 0.3048)
			(stroke
				(width 0.1)
				(type default)
			)
			(layer "F.Fab")
		)
		(fp_line
			(start 0.120396 0.2794)
			(end -0.12065 0.2794)
			(stroke
				(width 0.1)
				(type default)
			)
			(layer "F.Fab")
		)
		(fp_line
			(start -0.12065 -0.2794)
			(end 0.12065 -0.2794)
			(stroke
				(width 0.1)
				(type default)
			)
			(layer "F.Fab")
		)
		(fp_line
			(start 0.12065 -0.2794)
			(end 0.12065 -0.3048)
			(stroke
				(width 0.1)
				(type default)
			)
			(layer "F.Fab")
		)
		(fp_line
			(start 0.12065 -0.3048)
			(end 0.67945 -0.3048)
			(stroke
				(width 0.1)
				(type default)
			)
			(layer "F.Fab")
		)
		(fp_line
			(start 0.67945 -0.3048)
			(end 0.67945 0.3048)
			(stroke
				(width 0.1)
				(type default)
			)
			(layer "F.Fab")
		)
		(fp_line
			(start -0.67945 -0.305054)
			(end -0.12065 -0.305054)
			(stroke
				(width 0.1)
				(type default)
			)
			(layer "F.Fab")
		)
		(fp_line
			(start -0.12065 -0.305054)
			(end -0.12065 -0.2794)
			(stroke
				(width 0.1)
				(type default)
			)
			(layer "F.Fab")
		)
		(pad "1" smd circle
			(at -0.40005 0 270)
			(size 0 0)
			(layers "F.Cu" "F.Mask" "F.Paste")
			(net "GND")
		)
		(pad "2" smd circle
			(at 0.40005 0 270)
			(size 0 0)
			(layers "F.Cu" "F.Mask" "F.Paste")
			(net "PRSNT_GPU_N")
		)
	)
	(footprint ""
		(layer "F.Cu")
		(at 242.447318 -266.873228)
		(property "Reference" "R6136"
			(at 0 0 0)
			(layer "F.SilkS")
			(hide yes)
			(effects
				(font
					(size 1.27 1.27)
				)
			)
		)
		(property "Value" ""
			(at 0 0 0)
			(layer "F.Fab")
			(effects
				(font
					(size 1.27 1.27)
				)
			)
		)
		(duplicate_pad_numbers_are_jumpers no)
		(fp_line
			(start -2.576322 -1.1303)
			(end 2.576322 -1.1303)
			(stroke
				(width 0.1524)
				(type default)
			)
			(layer "F.SilkS")
		)
		(fp_line
			(start -2.576322 1.1303)
			(end -2.576322 -1.1303)
			(stroke
				(width 0.1524)
				(type default)
			)
			(layer "F.SilkS")
		)
		(fp_line
			(start 2.576322 -1.1303)
			(end 2.576322 1.1303)
			(stroke
				(width 0.1524)
				(type default)
			)
			(layer "F.SilkS")
		)
		(fp_line
			(start 2.576322 1.1303)
			(end -2.576322 1.1303)
			(stroke
				(width 0.1524)
				(type default)
			)
			(layer "F.SilkS")
		)
		(fp_line
			(start -1.649984 -0.899922)
			(end -1.649984 0.899922)
			(stroke
				(width 0.1)
				(type default)
			)
			(layer "F.Fab")
		)
		(fp_line
			(start -1.649984 0.899922)
			(end 1.649984 0.899922)
			(stroke
				(width 0.1)
				(type default)
			)
			(layer "F.Fab")
		)
		(fp_line
			(start 1.649984 -0.899922)
			(end -1.649984 -0.899922)
			(stroke
				(width 0.1)
				(type default)
			)
			(layer "F.Fab")
		)
		(fp_line
			(start 1.649984 0.899922)
			(end 1.649984 -0.899922)
			(stroke
				(width 0.1)
				(type default)
			)
			(layer "F.Fab")
		)
		(pad "1A" smd rect
			(at -1.700022 0)
			(size 1.4986 2.0066)
			(layers "F.Cu" "F.Mask" "F.Paste")
			(net "P1V25_PEX2")
		)
		(pad "1B" smd rect
			(at -1.077722 0)
			(size 0.254 0.508)
			(layers "F.Cu" "F.Mask" "F.Paste")
			(net "P1V25_PEX2")
		)
		(pad "2A" smd rect
			(at 1.700022 0)
			(size 1.4986 2.0066)
			(layers "F.Cu" "F.Mask" "F.Paste")
			(net "P1V25_SERDES_VDDPLL_PEX2")
		)
		(pad "2B" smd rect
			(at 1.077722 0)
			(size 0.254 0.508)
			(layers "F.Cu" "F.Mask" "F.Paste")
			(net "P1V25_SERDES_VDDPLL_PEX2")
		)
	)
	(footprint ""
		(layer "F.Cu")
		(at 382.420622 -26.666444 -90)
		(property "Reference" "R4079"
			(at 0 0 270)
			(layer "F.SilkS")
			(hide yes)
			(effects
				(font
					(size 1.27 1.27)
				)
			)
		)
		(property "Value" ""
			(at 0 0 270)
			(layer "F.Fab")
			(effects
				(font
					(size 1.27 1.27)
				)
			)
		)
		(duplicate_pad_numbers_are_jumpers no)
		(fp_line
			(start -0.7874 0.4064)
			(end -0.7874 -0.4064)
			(stroke
				(width 0.1524)
				(type default)
			)
			(layer "F.SilkS")
		)
		(fp_line
			(start 0.7874 0.4064)
			(end -0.7874 0.4064)
			(stroke
				(width 0.1524)
				(type default)
			)
			(layer "F.SilkS")
		)
		(fp_line
			(start -0.7874 -0.4064)
			(end 0.7874 -0.4064)
			(stroke
				(width 0.1524)
				(type default)
			)
			(layer "F.SilkS")
		)
		(fp_line
			(start 0.7874 -0.4064)
			(end 0.7874 0.4064)
			(stroke
				(width 0.1524)
				(type default)
			)
			(layer "F.SilkS")
		)
		(fp_line
			(start -0.67945 0.3048)
			(end -0.67945 -0.305054)
			(stroke
				(width 0.1)
				(type default)
			)
			(layer "F.Fab")
		)
		(fp_line
			(start -0.12065 0.3048)
			(end -0.67945 0.3048)
			(stroke
				(width 0.1)
				(type default)
			)
			(layer "F.Fab")
		)
		(fp_line
			(start 0.120396 0.3048)
			(end 0.120396 0.2794)
			(stroke
				(width 0.1)
				(type default)
			)
			(layer "F.Fab")
		)
		(fp_line
			(start 0.67945 0.3048)
			(end 0.120396 0.3048)
			(stroke
				(width 0.1)
				(type default)
			)
			(layer "F.Fab")
		)
		(fp_line
			(start -0.12065 0.2794)
			(end -0.12065 0.3048)
			(stroke
				(width 0.1)
				(type default)
			)
			(layer "F.Fab")
		)
		(fp_line
			(start 0.120396 0.2794)
			(end -0.12065 0.2794)
			(stroke
				(width 0.1)
				(type default)
			)
			(layer "F.Fab")
		)
		(fp_line
			(start -0.12065 -0.2794)
			(end 0.12065 -0.2794)
			(stroke
				(width 0.1)
				(type default)
			)
			(layer "F.Fab")
		)
		(fp_line
			(start 0.12065 -0.2794)
			(end 0.12065 -0.3048)
			(stroke
				(width 0.1)
				(type default)
			)
			(layer "F.Fab")
		)
		(fp_line
			(start 0.12065 -0.3048)
			(end 0.67945 -0.3048)
			(stroke
				(width 0.1)
				(type default)
			)
			(layer "F.Fab")
		)
		(fp_line
			(start 0.67945 -0.3048)
			(end 0.67945 0.3048)
			(stroke
				(width 0.1)
				(type default)
			)
			(layer "F.Fab")
		)
		(fp_line
			(start -0.67945 -0.305054)
			(end -0.12065 -0.305054)
			(stroke
				(width 0.1)
				(type default)
			)
			(layer "F.Fab")
		)
		(fp_line
			(start -0.12065 -0.305054)
			(end -0.12065 -0.2794)
			(stroke
				(width 0.1)
				(type default)
			)
			(layer "F.Fab")
		)
		(pad "1" smd circle
			(at -0.40005 0 270)
			(size 0 0)
			(layers "F.Cu" "F.Mask" "F.Paste")
			(net "PRSNT_SSD13_R_N")
		)
		(pad "2" smd circle
			(at 0.40005 0 270)
			(size 0 0)
			(layers "F.Cu" "F.Mask" "F.Paste")
			(net "PRSNT_SSD13_N")
		)
	)
	(footprint ""
		(layer "F.Cu")
		(at 314.861448 -132.601208 180)
		(property "Reference" "C443"
			(at 0 0 180)
			(layer "F.SilkS")
			(hide yes)
			(effects
				(font
					(size 1.27 1.27)
				)
			)
		)
		(property "Value" ""
			(at 0 0 180)
			(layer "F.Fab")
			(effects
				(font
					(size 1.27 1.27)
				)
			)
		)
		(duplicate_pad_numbers_are_jumpers no)
		(fp_line
			(start 0.299974 0.150114)
			(end -0.299974 0.150114)
			(stroke
				(width 0.1)
				(type default)
			)
			(layer "F.Fab")
		)
		(fp_line
			(start 0.299974 -0.150114)
			(end 0.299974 0.150114)
			(stroke
				(width 0.1)
				(type default)
			)
			(layer "F.Fab")
		)
		(fp_line
			(start -0.299974 0.150114)
			(end -0.299974 -0.150114)
			(stroke
				(width 0.1)
				(type default)
			)
			(layer "F.Fab")
		)
		(fp_line
			(start -0.299974 -0.150114)
			(end 0.299974 -0.150114)
			(stroke
				(width 0.1)
				(type default)
			)
			(layer "F.Fab")
		)
		(pad "1" smd rect
			(at -0.2667 0 180)
			(size 0.3048 0.381)
			(layers "F.Cu" "F.Mask" "F.Paste")
			(net "P5E_PEX2_STN0_TX_DP<5>")
		)
		(pad "2" smd rect
			(at 0.2667 0 180)
			(size 0.3048 0.381)
			(layers "F.Cu" "F.Mask" "F.Paste")
			(net "P5E_PEX2_STN0_TX_C_DP<5>")
		)
	)
)
